# S9S_MB_2U (Grand Teton) — schematic netlist excerpt (pin names and nets, part order shuffled) for the footprints in the layout excerpt that follows; sources: Cadence DE-HDL packaged netlist, KiCad conversion of 03242023_DA0F0TMBIJ0_F0T_Motherboard_J_brd_V01_OCP.brd

R2450  Q_RES  33.2 1% CHIP  pkg 0402LF  page 241 : A = SMB_VR_3V3AUX_SDA ; B = SMB_VR_3V3AUX_SDA_R1
PC2261  Q_CAP  22UF 16V 20% X6S  pkg C0805  page 259 : A = SW_P3V3_AUX_FLT ; B = GND
PC256  Q_CAP  100NF 50V 10% X7R  pkg C0402  page 269 : A = SW_PVCCIN_CPU0_BOOT6_R ; B = SW_PVCCIN_CPU0_BOOTR6

(kicad_pcb
	(version 20260206)
	(generator "pcbnew")
	(generator_version "10.0")
	(general
		(thickness 1.6)
		(legacy_teardrops no)
	)
	(paper "A4")
	(title_block
		(title "03242023_DA0F0TMBIJ0_F0T_Motherboard_J_brd_V01_OCP.brd")
		(comment 1 "Grand Teton / footprints 1753-1755 of 6105")
	)
	(layers
		(0 "F.Cu" signal "TOP")
		(4 "In1.Cu" signal "GND")
		(6 "In2.Cu" signal "IN1")
		(8 "In3.Cu" signal "GND1")
		(10 "In4.Cu" signal "IN2")
		(12 "In5.Cu" signal "GND2")
		(14 "In6.Cu" signal "IN3")
		(16 "In7.Cu" signal "GND3")
		(18 "In8.Cu" signal "VCC")
		(20 "In9.Cu" signal "VCC1")
		(22 "In10.Cu" signal "GND4")
		(24 "In11.Cu" signal "IN4")
		(26 "In12.Cu" signal "GND5")
		(28 "In13.Cu" signal "IN5")
		(30 "In14.Cu" signal "GND6")
		(32 "In15.Cu" signal "IN6")
		(34 "In16.Cu" signal "GND7")
		(2 "B.Cu" signal "BOTTOM")
		(9 "F.Adhes" user "F.Adhesive")
		(11 "B.Adhes" user "B.Adhesive")
		(13 "F.Paste" user "Package Geometry/Pastemask Top")
		(15 "B.Paste" user "Package Geometry/Pastemask Bottom")
		(5 "F.SilkS" user "Ref Des/Silkscreen Top")
		(7 "B.SilkS" user "Ref Des/Silkscreen Bottom")
		(1 "F.Mask" user "Board Geometry/Soldermask Top")
		(3 "B.Mask" user "Board Geometry/Soldermask Bottom")
		(17 "Dwgs.User" user "User.Drawings")
		(19 "Cmts.User" user "User.Comments")
		(21 "Eco1.User" user "User.Eco1")
		(23 "Eco2.User" user "User.Eco2")
		(25 "Edge.Cuts" user "Board Geometry/Outline")
		(27 "Margin" user)
		(31 "F.CrtYd" user "Package Geometry/Place Bound Top")
		(29 "B.CrtYd" user "Package Geometry/Place Bound Bottom")
		(35 "F.Fab" user "Ref Des/Assembly Top")
		(33 "B.Fab" user "Ref Des/Assembly Bottom")
	)
	(footprint ""
		(layer "F.Cu")
		(at 338.56295 -341.729822 -90)
		(property "Reference" "PC256"
			(at 0 0 270)
			(layer "F.SilkS")
			(hide yes)
			(effects
				(font
					(size 1.27 1.27)
				)
			)
		)
		(property "Value" ""
			(at 0 0 270)
			(layer "F.Fab")
			(effects
				(font
					(size 1.27 1.27)
				)
			)
		)
		(duplicate_pad_numbers_are_jumpers no)
		(fp_line
			(start -0.7874 0.4064)
			(end -0.7874 -0.4064)
			(stroke
				(width 0.1524)
				(type default)
			)
			(layer "F.SilkS")
		)
		(fp_line
			(start 0.7874 0.4064)
			(end -0.7874 0.4064)
			(stroke
				(width 0.1524)
				(type default)
			)
			(layer "F.SilkS")
		)
		(fp_line
			(start -0.7874 -0.4064)
			(end 0.7874 -0.4064)
			(stroke
				(width 0.1524)
				(type default)
			)
			(layer "F.SilkS")
		)
		(fp_line
			(start 0.7874 -0.4064)
			(end 0.7874 0.4064)
			(stroke
				(width 0.1524)
				(type default)
			)
			(layer "F.SilkS")
		)
		(fp_line
			(start -0.67945 0.3048)
			(end -0.67945 -0.305054)
			(stroke
				(width 0.1)
				(type default)
			)
			(layer "F.Fab")
		)
		(fp_line
			(start -0.12065 0.3048)
			(end -0.67945 0.3048)
			(stroke
				(width 0.1)
				(type default)
			)
			(layer "F.Fab")
		)
		(fp_line
			(start 0.120396 0.3048)
			(end 0.120396 0.2794)
			(stroke
				(width 0.1)
				(type default)
			)
			(layer "F.Fab")
		)
		(fp_line
			(start 0.67945 0.3048)
			(end 0.120396 0.3048)
			(stroke
				(width 0.1)
				(type default)
			)
			(layer "F.Fab")
		)
		(fp_line
			(start -0.12065 0.2794)
			(end -0.12065 0.3048)
			(stroke
				(width 0.1)
				(type default)
			)
			(layer "F.Fab")
		)
		(fp_line
			(start 0.120396 0.2794)
			(end -0.12065 0.2794)
			(stroke
				(width 0.1)
				(type default)
			)
			(layer "F.Fab")
		)
		(fp_line
			(start -0.12065 -0.2794)
			(end 0.12065 -0.2794)
			(stroke
				(width 0.1)
				(type default)
			)
			(layer "F.Fab")
		)
		(fp_line
			(start 0.12065 -0.2794)
			(end 0.12065 -0.3048)
			(stroke
				(width 0.1)
				(type default)
			)
			(layer "F.Fab")
		)
		(fp_line
			(start 0.12065 -0.3048)
			(end 0.67945 -0.3048)
			(stroke
				(width 0.1)
				(type default)
			)
			(layer "F.Fab")
		)
		(fp_line
			(start 0.67945 -0.3048)
			(end 0.67945 0.3048)
			(stroke
				(width 0.1)
				(type default)
			)
			(layer "F.Fab")
		)
		(fp_line
			(start -0.67945 -0.305054)
			(end -0.12065 -0.305054)
			(stroke
				(width 0.1)
				(type default)
			)
			(layer "F.Fab")
		)
		(fp_line
			(start -0.12065 -0.305054)
			(end -0.12065 -0.2794)
			(stroke
				(width 0.1)
				(type default)
			)
			(layer "F.Fab")
		)
		(pad "1" smd circle
			(at -0.40005 0 270)
			(size 0 0)
			(layers "F.Cu" "F.Mask" "F.Paste")
			(net "SW_PVCCIN_CPU0_BOOT6_R")
		)
		(pad "2" smd circle
			(at 0.40005 0 270)
			(size 0 0)
			(layers "F.Cu" "F.Mask" "F.Paste")
			(net "SW_PVCCIN_CPU0_BOOTR6")
		)
	)
	(footprint ""
		(layer "F.Cu")
		(at 458.720444 -70.271386 -90)
		(property "Reference" "PC2261"
			(at 0 0 270)
			(layer "F.SilkS")
			(hide yes)
			(effects
				(font
					(size 1.27 1.27)
				)
			)
		)
		(property "Value" ""
			(at 0 0 270)
			(layer "F.Fab")
			(effects
				(font
					(size 1.27 1.27)
				)
			)
		)
		(duplicate_pad_numbers_are_jumpers no)
		(fp_line
			(start -1.524 0.762)
			(end -1.524 -0.762)
			(stroke
				(width 0.1524)
				(type default)
			)
			(layer "F.SilkS")
		)
		(fp_line
			(start 1.524 0.762)
			(end -1.524 0.762)
			(stroke
				(width 0.1524)
				(type default)
			)
			(layer "F.SilkS")
		)
		(fp_line
			(start -1.524 -0.762)
			(end 1.524 -0.762)
			(stroke
				(width 0.1524)
				(type default)
			)
			(layer "F.SilkS")
		)
		(fp_line
			(start 1.524 -0.762)
			(end 1.524 0.762)
			(stroke
				(width 0.1524)
				(type default)
			)
			(layer "F.SilkS")
		)
		(fp_line
			(start -1.1049 0.724916)
			(end 1.1049 0.724916)
			(stroke
				(width 0.1)
				(type default)
			)
			(layer "F.Fab")
		)
		(fp_line
			(start 1.1049 0.724916)
			(end 1.1049 -0.724916)
			(stroke
				(width 0.1)
				(type default)
			)
			(layer "F.Fab")
		)
		(fp_line
			(start -1.1049 -0.724916)
			(end -1.1049 0.724916)
			(stroke
				(width 0.1)
				(type default)
			)
			(layer "F.Fab")
		)
		(fp_line
			(start 1.1049 -0.724916)
			(end -1.1049 -0.724916)
			(stroke
				(width 0.1)
				(type default)
			)
			(layer "F.Fab")
		)
		(pad "1" smd rect
			(at -0.889 0 90)
			(size 1.016 1.27)
			(layers "F.Cu" "F.Mask" "F.Paste")
			(net "SW_P3V3_AUX_FLT")
		)
		(pad "2" smd rect
			(at 0.889 0 90)
			(size 1.016 1.27)
			(layers "F.Cu" "F.Mask" "F.Paste")
			(net "GND")
		)
	)
	(footprint ""
		(layer "F.Cu")
		(at 30.49524 -122.380502 90)
		(property "Reference" "R2450"
			(at 0 0 90)
			(layer "F.SilkS")
			(hide yes)
			(effects
				(font
					(size 1.27 1.27)
				)
			)
		)
		(property "Value" ""
			(at 0 0 90)
			(layer "F.Fab")
			(effects
				(font
					(size 1.27 1.27)
				)
			)
		)
		(duplicate_pad_numbers_are_jumpers no)
		(fp_line
			(start 0.7874 -0.4064)
			(end 0.7874 0.4064)
			(stroke
				(width 0.1524)
				(type default)
			)
			(layer "F.SilkS")
		)
		(fp_line
			(start -0.7874 -0.4064)
			(end 0.7874 -0.4064)
			(stroke
				(width 0.1524)
				(type default)
			)
			(layer "F.SilkS")
		)
		(fp_line
			(start 0.7874 0.4064)
			(end -0.7874 0.4064)
			(stroke
				(width 0.1524)
				(type default)
			)
			(layer "F.SilkS")
		)
		(fp_line
			(start -0.7874 0.4064)
			(end -0.7874 -0.4064)
			(stroke
				(width 0.1524)
				(type default)
			)
			(layer "F.SilkS")
		)
		(fp_line
			(start -0.12065 -0.305054)
			(end -0.12065 -0.2794)
			(stroke
				(width 0.1)
				(type default)
			)
			(layer "F.Fab")
		)
		(fp_line
			(start -0.67945 -0.305054)
			(end -0.12065 -0.305054)
			(stroke
				(width 0.1)
				(type default)
			)
			(layer "F.Fab")
		)
		(fp_line
			(start 0.67945 -0.3048)
			(end 0.67945 0.3048)
			(stroke
				(width 0.1)
				(type default)
			)
			(layer "F.Fab")
		)
		(fp_line
			(start 0.12065 -0.3048)
			(end 0.67945 -0.3048)
			(stroke
				(width 0.1)
				(type default)
			)
			(layer "F.Fab")
		)
		(fp_line
			(start 0.12065 -0.2794)
			(end 0.12065 -0.3048)
			(stroke
				(width 0.1)
				(type default)
			)
			(layer "F.Fab")
		)
		(fp_line
			(start -0.12065 -0.2794)
			(end 0.12065 -0.2794)
			(stroke
				(width 0.1)
				(type default)
			)
			(layer "F.Fab")
		)
		(fp_line
			(start 0.120396 0.2794)
			(end -0.12065 0.2794)
			(stroke
				(width 0.1)
				(type default)
			)
			(layer "F.Fab")
		)
		(fp_line
			(start -0.12065 0.2794)
			(end -0.12065 0.3048)
			(stroke
				(width 0.1)
				(type default)
			)
			(layer "F.Fab")
		)
		(fp_line
			(start 0.67945 0.3048)
			(end 0.120396 0.3048)
			(stroke
				(width 0.1)
				(type default)
			)
			(layer "F.Fab")
		)
		(fp_line
			(start 0.120396 0.3048)
			(end 0.120396 0.2794)
			(stroke
				(width 0.1)
				(type default)
			)
			(layer "F.Fab")
		)
		(fp_line
			(start -0.12065 0.3048)
			(end -0.67945 0.3048)
			(stroke
				(width 0.1)
				(type default)
			)
			(layer "F.Fab")
		)
		(fp_line
			(start -0.67945 0.3048)
			(end -0.67945 -0.305054)
			(stroke
				(width 0.1)
				(type default)
			)
			(layer "F.Fab")
		)
		(pad "1" smd circle
			(at -0.40005 0 90)
			(size 0 0)
			(layers "F.Cu" "F.Mask" "F.Paste")
			(net "SMB_VR_3V3AUX_SDA")
		)
		(pad "2" smd circle
			(at 0.40005 0 90)
			(size 0 0)
			(layers "F.Cu" "F.Mask" "F.Paste")
			(net "SMB_VR_3V3AUX_SDA_R1")
		)
	)
)
